# BASEBOARD_FAB2 (Tioga Pass) — schematic netlist excerpt (pin names and nets, part order shuffled) for the footprints in the layout excerpt that follows; sources: Cadence DE-HDL packaged netlist, KiCad conversion of Wiwynn_Tioga_Pass_MB.brd

R9B7  887R2F-L-GP  1%  pkg SMD-RG  page 186 : \1\ = FM_MEZZA_PRSNT1_N ; \2\ = GND
R7P15  RES  240 1.0% EMPTY  pkg 0402  page 90 : A = GND ; B = PD_CPU1_KSFC_DIS

(kicad_pcb
	(version 20260206)
	(generator "pcbnew")
	(generator_version "10.0")
	(general
		(thickness 1.6)
		(legacy_teardrops no)
	)
	(paper "A4")
	(title_block
		(title "Wiwynn_Tioga_Pass_MB.brd")
		(comment 1 "Tioga Pass / footprints 2339-2341 of 4770")
	)
	(layers
		(0 "F.Cu" signal "TOP")
		(4 "In1.Cu" signal "L2GND")
		(6 "In2.Cu" signal "L3")
		(8 "In3.Cu" signal "L4GND")
		(10 "In4.Cu" signal "L5")
		(12 "In5.Cu" signal "L6GND")
		(14 "In6.Cu" signal "L7VCC")
		(16 "In7.Cu" signal "L8VCC")
		(18 "In8.Cu" signal "L9GND")
		(20 "In9.Cu" signal "L10")
		(22 "In10.Cu" signal "L11GND")
		(24 "In11.Cu" signal "L12")
		(26 "In12.Cu" signal "L13GND")
		(2 "B.Cu" signal "BOTTOM")
		(9 "F.Adhes" user "F.Adhesive")
		(11 "B.Adhes" user "B.Adhesive")
		(13 "F.Paste" user "Package Geometry/Pastemask Top")
		(15 "B.Paste" user "Package Geometry/Pastemask Bottom")
		(5 "F.SilkS" user "Ref Des/Silkscreen Top")
		(7 "B.SilkS" user "Ref Des/Silkscreen Bottom")
		(1 "F.Mask" user "Board Geometry/Soldermask Top")
		(3 "B.Mask" user "Board Geometry/Soldermask Bottom")
		(17 "Dwgs.User" user "User.Drawings")
		(19 "Cmts.User" user "User.Comments")
		(21 "Eco1.User" user "User.Eco1")
		(23 "Eco2.User" user "User.Eco2")
		(25 "Edge.Cuts" user "Board Geometry/Outline")
		(27 "Margin" user)
		(31 "F.CrtYd" user "Package Geometry/Place Bound Top")
		(29 "B.CrtYd" user "Package Geometry/Place Bound Bottom")
		(35 "F.Fab" user "Ref Des/Assembly Top")
		(33 "B.Fab" user "Ref Des/Assembly Bottom")
	)
	(footprint ""
		(layer "B.Cu")
		(at 221.488 -28.194)
		(property "Reference" ""
			(at 0 0 0)
			(layer "B.SilkS")
			(hide yes)
			(effects
				(font
					(size 1.27 1.27)
				)
				(justify mirror)
			)
		)
		(property "Value" ""
			(at 0 0 0)
			(layer "B.Fab")
			(effects
				(font
					(size 1.27 1.27)
				)
				(justify mirror)
			)
		)
		(duplicate_pad_numbers_are_jumpers no)
		(fp_poly
			(pts
				(arc
					(start 2.032 0)
					(mid -2.032 0)
					(end 2.032 0)
				)
			)
			(stroke
				(width 0)
				(type default)
			)
			(fill no)
			(layer "B.CrtYd")
		)
		(pad "1" smd circle
			(at 0 0 180)
			(size 1.016 1.016)
			(layers "B.Cu" "B.Mask" "B.Paste")
			(net "Net_396")
		)
		(zone
			(layers "F.Cu" "B.Cu" "In1.Cu" "In2.Cu" "In3.Cu" "In4.Cu" "In5.Cu" "In6.Cu"
				"In7.Cu" "In8.Cu" "In9.Cu" "In10.Cu" "In11.Cu" "In12.Cu"
			)
			(hatch none 0.5)
			(connect_pads
				(clearance 0)
			)
			(min_thickness 0.25)
			(keepout
				(tracks allowed)
				(vias not_allowed)
				(pads allowed)
				(copperpour not_allowed)
				(footprints allowed)
			)
			(placement
				(enabled no)
				(sheetname "")
			)
			(fill
				(thermal_gap 0.5)
				(thermal_bridge_width 0.5)
				(island_removal_mode 0)
			)
			(polygon
				(pts
					(arc
						(start 223.012 -28.194)
						(mid 219.964 -28.194)
						(end 223.012 -28.194)
					)
				)
			)
		)
		(zone
			(layer "B.Cu")
			(hatch none 0.5)
			(connect_pads
				(clearance 0)
			)
			(min_thickness 0.25)
			(keepout
				(tracks not_allowed)
				(vias allowed)
				(pads allowed)
				(copperpour not_allowed)
				(footprints allowed)
			)
			(placement
				(enabled no)
				(sheetname "")
			)
			(fill
				(thermal_gap 0.5)
				(thermal_bridge_width 0.5)
				(island_removal_mode 0)
			)
			(polygon
				(pts
					(arc
						(start 223.012 -28.194)
						(mid 219.964 -28.194)
						(end 223.012 -28.194)
					)
				)
			)
		)
	)
	(footprint ""
		(layer "B.Cu")
		(at 116.332 -74.93 90)
		(property "Reference" "R7P15"
			(at 0 0 90)
			(layer "B.SilkS")
			(hide yes)
			(effects
				(font
					(size 1.27 1.27)
				)
				(justify mirror)
			)
		)
		(property "Value" ""
			(at 0 0 90)
			(layer "B.Fab")
			(effects
				(font
					(size 1.27 1.27)
				)
				(justify mirror)
			)
		)
		(duplicate_pad_numbers_are_jumpers no)
		(fp_poly
			(pts
				(xy 0.2794 -0.1016) (xy -0.2794 -0.1016) (xy -0.2794 0.9906) (xy 0.2794 0.9906)
			)
			(stroke
				(width 0)
				(type default)
			)
			(fill no)
			(layer "B.CrtYd")
		)
		(fp_line
			(start 0.2794 -0.1016)
			(end 0.2794 0.9906)
			(stroke
				(width 0.1)
				(type default)
			)
			(layer "B.Fab")
		)
		(fp_line
			(start -0.2794 -0.1016)
			(end 0.2794 -0.1016)
			(stroke
				(width 0.1)
				(type default)
			)
			(layer "B.Fab")
		)
		(fp_line
			(start 0.2794 0.9906)
			(end -0.2794 0.9906)
			(stroke
				(width 0.1)
				(type default)
			)
			(layer "B.Fab")
		)
		(fp_line
			(start -0.2794 0.9906)
			(end -0.2794 -0.1016)
			(stroke
				(width 0.1)
				(type default)
			)
			(layer "B.Fab")
		)
		(pad "1" smd rect
			(at 0 0 270)
			(size 0.508 0.508)
			(layers "B.Cu" "B.Mask" "B.Paste")
			(net "GND")
		)
		(pad "2" smd rect
			(at 0 0.889 270)
			(size 0.508 0.508)
			(layers "B.Cu" "B.Mask" "B.Paste")
			(net "PD_CPU1_KSFC_DIS")
		)
		(zone
			(layer "B.Cu")
			(hatch none 0.5)
			(connect_pads
				(clearance 0)
			)
			(min_thickness 0.25)
			(keepout
				(tracks allowed)
				(vias not_allowed)
				(pads allowed)
				(copperpour not_allowed)
				(footprints allowed)
			)
			(placement
				(enabled no)
				(sheetname "")
			)
			(fill
				(thermal_gap 0.5)
				(thermal_bridge_width 0.5)
				(island_removal_mode 0)
			)
			(polygon
				(pts
					(xy 116.586 -75.184) (xy 116.586 -74.676) (xy 116.967 -74.676) (xy 116.967 -75.184)
				)
			)
		)
		(zone
			(layer "B.Cu")
			(hatch none 0.5)
			(connect_pads
				(clearance 0)
			)
			(min_thickness 0.25)
			(keepout
				(tracks not_allowed)
				(vias allowed)
				(pads allowed)
				(copperpour not_allowed)
				(footprints allowed)
			)
			(placement
				(enabled no)
				(sheetname "")
			)
			(fill
				(thermal_gap 0.5)
				(thermal_bridge_width 0.5)
				(island_removal_mode 0)
			)
			(polygon
				(pts
					(xy 116.967 -75.184) (xy 116.967 -74.676) (xy 116.586 -74.676) (xy 116.586 -75.184)
				)
			)
		)
	)
	(footprint ""
		(layer "B.Cu")
		(at 492.4044 -116.082318)
		(property "Reference" "R9B7"
			(at 0 0 0)
			(layer "B.SilkS")
			(hide yes)
			(effects
				(font
					(size 1.27 1.27)
				)
				(justify mirror)
			)
		)
		(property "Value" "*"
			(at -0.064008 -4.108196 0)
			(unlocked yes)
			(layer "B.Fab")
			(hide yes)
			(effects
				(font
					(size 1.27 1.016)
					(thickness 0.1524)
				)
				(justify mirror)
			)
		)
		(property "Device Type" "887R2F-L-GP_SMD-RG-887R2F-L-GPA"
			(at -0.064008 -5.632196 0)
			(unlocked yes)
			(layer "B.Fab")
			(hide yes)
			(effects
				(font
					(size 1.27 1.016)
					(thickness 0.1524)
				)
				(justify mirror)
			)
		)
		(duplicate_pad_numbers_are_jumpers no)
		(fp_line
			(start -0.508 -0.9398)
			(end 0.508 -0.9398)
			(stroke
				(width 0.1524)
				(type default)
			)
			(layer "B.SilkS")
		)
		(fp_line
			(start 0.508 -0.9398)
			(end 0.508 0.9398)
			(stroke
				(width 0.1524)
				(type default)
			)
			(layer "B.SilkS")
		)
		(fp_rect
			(start 0.508 0.9398)
			(end -0.508 -0.9398)
			(stroke
				(width 0)
				(type default)
			)
			(fill no)
			(layer "B.CrtYd")
		)
		(fp_rect
			(start 0.508 0.9398)
			(end -0.508 -0.9398)
			(stroke
				(width 0)
				(type default)
			)
			(fill no)
			(layer "B.Fab")
		)
		(pad "1" smd custom
			(at 0 -0.4445 180)
			(size 0.1397 0.1397)
			(layers "B.Cu" "B.Mask" "B.Paste")
			(net "FM_MEZZA_PRSNT1_N")
			(options
				(clearance outline)
				(anchor circle)
			)
			(primitives
				(gr_poly
					(pts
						(arc
							(start -0.1778 0.2794)
							(mid -0.249642 0.249642)
							(end -0.2794 0.1778)
						)
						(arc
							(start -0.2794 -0.1778)
							(mid -0.249642 -0.249642)
							(end -0.1778 -0.2794)
						)
						(arc
							(start 0.1778 -0.2794)
							(mid 0.249642 -0.249642)
							(end 0.2794 -0.1778)
						)
						(arc
							(start 0.2794 0.1778)
							(mid 0.249642 0.249642)
							(end 0.1778 0.2794)
						)
					)
					(width 0)
					(fill yes)
				)
			)
		)
		(pad "2" smd custom
			(at 0 0.4445 180)
			(size 0.1397 0.1397)
			(layers "B.Cu" "B.Mask" "B.Paste")
			(net "GND")
			(options
				(clearance outline)
				(anchor circle)
			)
			(primitives
				(gr_poly
					(pts
						(arc
							(start -0.1778 0.2794)
							(mid -0.249642 0.249642)
							(end -0.2794 0.1778)
						)
						(arc
							(start -0.2794 -0.1778)
							(mid -0.249642 -0.249642)
							(end -0.1778 -0.2794)
						)
						(arc
							(start 0.1778 -0.2794)
							(mid 0.249642 -0.249642)
							(end 0.2794 -0.1778)
						)
						(arc
							(start 0.2794 0.1778)
							(mid 0.249642 0.249642)
							(end 0.1778 0.2794)
						)
					)
					(width 0)
					(fill yes)
				)
			)
		)
	)
)
